# BASEBOARD_FAB2 (Tioga Pass) — schematic netlist excerpt (pin names and nets, part order shuffled) for the footprints in the layout excerpt that follows; sources: Cadence DE-HDL packaged netlist, KiCad conversion of Wiwynn_Tioga_Pass_MB.brd

R7G4  RES  0.0 5% CHIP  pkg 0402  page 215 : A = SVID_ALERT_PVDDQ_ABC ; B = SVID_ALERT1_CPU0_R_N

(kicad_pcb
	(version 20260206)
	(generator "pcbnew")
	(generator_version "10.0")
	(general
		(thickness 1.6)
		(legacy_teardrops no)
	)
	(paper "A4")
	(title_block
		(title "Wiwynn_Tioga_Pass_MB.brd")
		(comment 1 "Tioga Pass / footprints 1446-1446 of 4770")
	)
	(layers
		(0 "F.Cu" signal "TOP")
		(4 "In1.Cu" signal "L2GND")
		(6 "In2.Cu" signal "L3")
		(8 "In3.Cu" signal "L4GND")
		(10 "In4.Cu" signal "L5")
		(12 "In5.Cu" signal "L6GND")
		(14 "In6.Cu" signal "L7VCC")
		(16 "In7.Cu" signal "L8VCC")
		(18 "In8.Cu" signal "L9GND")
		(20 "In9.Cu" signal "L10")
		(22 "In10.Cu" signal "L11GND")
		(24 "In11.Cu" signal "L12")
		(26 "In12.Cu" signal "L13GND")
		(2 "B.Cu" signal "BOTTOM")
		(9 "F.Adhes" user "F.Adhesive")
		(11 "B.Adhes" user "B.Adhesive")
		(13 "F.Paste" user "Package Geometry/Pastemask Top")
		(15 "B.Paste" user "Package Geometry/Pastemask Bottom")
		(5 "F.SilkS" user "Ref Des/Silkscreen Top")
		(7 "B.SilkS" user "Ref Des/Silkscreen Bottom")
		(1 "F.Mask" user "Board Geometry/Soldermask Top")
		(3 "B.Mask" user "Board Geometry/Soldermask Bottom")
		(17 "Dwgs.User" user "User.Drawings")
		(19 "Cmts.User" user "User.Comments")
		(21 "Eco1.User" user "User.Eco1")
		(23 "Eco2.User" user "User.Eco2")
		(25 "Edge.Cuts" user "Board Geometry/Outline")
		(27 "Margin" user)
		(31 "F.CrtYd" user "Package Geometry/Place Bound Top")
		(29 "B.CrtYd" user "Package Geometry/Place Bound Bottom")
		(35 "F.Fab" user "Ref Des/Assembly Top")
		(33 "B.Fab" user "Ref Des/Assembly Bottom")
	)
	(footprint ""
		(layer "F.Cu")
		(at 338.836 -15.494 -90)
		(property "Reference" "R7G4"
			(at 0 0 270)
			(layer "F.SilkS")
			(hide yes)
			(effects
				(font
					(size 1.27 1.27)
				)
			)
		)
		(property "Value" ""
			(at 0 0 270)
			(layer "F.Fab")
			(effects
				(font
					(size 1.27 1.27)
				)
			)
		)
		(duplicate_pad_numbers_are_jumpers no)
		(fp_rect
			(start 0.2794 0.9906)
			(end -0.2794 -0.1016)
			(stroke
				(width 0)
				(type default)
			)
			(fill no)
			(layer "F.CrtYd")
		)
		(fp_line
			(start -0.2794 0.9906)
			(end 0.2794 0.9906)
			(stroke
				(width 0.1)
				(type default)
			)
			(layer "F.Fab")
		)
		(fp_line
			(start 0.2794 0.9906)
			(end 0.2794 -0.1016)
			(stroke
				(width 0.1)
				(type default)
			)
			(layer "F.Fab")
		)
		(fp_line
			(start -0.2794 -0.1016)
			(end -0.2794 0.9906)
			(stroke
				(width 0.1)
				(type default)
			)
			(layer "F.Fab")
		)
		(fp_line
			(start 0.2794 -0.1016)
			(end -0.2794 -0.1016)
			(stroke
				(width 0.1)
				(type default)
			)
			(layer "F.Fab")
		)
		(pad "1" smd rect
			(at 0 0 270)
			(size 0.508 0.508)
			(layers "F.Cu" "F.Mask" "F.Paste")
			(net "SVID_ALERT_PVDDQ_ABC")
		)
		(pad "2" smd rect
			(at 0 0.889 270)
			(size 0.508 0.508)
			(layers "F.Cu" "F.Mask" "F.Paste")
			(net "SVID_ALERT1_CPU0_R_N")
		)
		(zone
			(layer "F.Cu")
			(hatch none 0.5)
			(connect_pads
				(clearance 0)
			)
			(min_thickness 0.25)
			(keepout
				(tracks not_allowed)
				(vias allowed)
				(pads allowed)
				(copperpour not_allowed)
				(footprints allowed)
			)
			(placement
				(enabled no)
				(sheetname "")
			)
			(fill
				(thermal_gap 0.5)
				(thermal_bridge_width 0.5)
				(island_removal_mode 0)
			)
			(polygon
				(pts
					(xy 338.201 -15.24) (xy 338.582 -15.24) (xy 338.582 -15.748) (xy 338.201 -15.748)
				)
			)
		)
		(zone
			(layer "F.Cu")
			(hatch none 0.5)
			(connect_pads
				(clearance 0)
			)
			(min_thickness 0.25)
			(keepout
				(tracks allowed)
				(vias not_allowed)
				(pads allowed)
				(copperpour not_allowed)
				(footprints allowed)
			)
			(placement
				(enabled no)
				(sheetname "")
			)
			(fill
				(thermal_gap 0.5)
				(thermal_bridge_width 0.5)
				(island_removal_mode 0)
			)
			(polygon
				(pts
					(xy 338.201 -15.24) (xy 338.582 -15.24) (xy 338.582 -15.748) (xy 338.201 -15.748)
				)
			)
		)
	)
)
